# BASEBOARD_FAB2 (Tioga Pass) — schematic netlist excerpt (pin names and nets, part order shuffled) for the footprints in the layout excerpt that follows; sources: Cadence DE-HDL packaged netlist, KiCad conversion of Wiwynn_Tioga_Pass_MB.brd

R3P2  RES  0.0 5% CHIP  pkg 0402  page 121 : A = RMII_BMC_PCH_SPRNGVLLE_CRSDV ; B = RMII_BMC_PCH_SPRNGVLLE_CRSDV_R1
R1D25  RES  0.0 5% CHIP  pkg 0402  page 199 : A = SMB_BMC_PMBUS_STBY_LVC3_SDA ; B = SMB_3V3SB_HSC_SDA_R
C5B2  CAP_A  47UF 4V 20% X5R  pkg 0603V  page 220 : A = PVDDQ_DEF ; B = GND

(kicad_pcb
	(version 20260206)
	(generator "pcbnew")
	(generator_version "10.0")
	(general
		(thickness 1.6)
		(legacy_teardrops no)
	)
	(paper "A4")
	(title_block
		(title "Wiwynn_Tioga_Pass_MB.brd")
		(comment 1 "Tioga Pass / footprints 1528-1530 of 4770")
	)
	(layers
		(0 "F.Cu" signal "TOP")
		(4 "In1.Cu" signal "L2GND")
		(6 "In2.Cu" signal "L3")
		(8 "In3.Cu" signal "L4GND")
		(10 "In4.Cu" signal "L5")
		(12 "In5.Cu" signal "L6GND")
		(14 "In6.Cu" signal "L7VCC")
		(16 "In7.Cu" signal "L8VCC")
		(18 "In8.Cu" signal "L9GND")
		(20 "In9.Cu" signal "L10")
		(22 "In10.Cu" signal "L11GND")
		(24 "In11.Cu" signal "L12")
		(26 "In12.Cu" signal "L13GND")
		(2 "B.Cu" signal "BOTTOM")
		(9 "F.Adhes" user "F.Adhesive")
		(11 "B.Adhes" user "B.Adhesive")
		(13 "F.Paste" user "Package Geometry/Pastemask Top")
		(15 "B.Paste" user "Package Geometry/Pastemask Bottom")
		(5 "F.SilkS" user "Ref Des/Silkscreen Top")
		(7 "B.SilkS" user "Ref Des/Silkscreen Bottom")
		(1 "F.Mask" user "Board Geometry/Soldermask Top")
		(3 "B.Mask" user "Board Geometry/Soldermask Bottom")
		(17 "Dwgs.User" user "User.Drawings")
		(19 "Cmts.User" user "User.Comments")
		(21 "Eco1.User" user "User.Eco1")
		(23 "Eco2.User" user "User.Eco2")
		(25 "Edge.Cuts" user "Board Geometry/Outline")
		(27 "Margin" user)
		(31 "F.CrtYd" user "Package Geometry/Place Bound Top")
		(29 "B.CrtYd" user "Package Geometry/Place Bound Bottom")
		(35 "F.Fab" user "Ref Des/Assembly Top")
		(33 "B.Fab" user "Ref Des/Assembly Bottom")
	)
	(footprint ""
		(layer "F.Cu")
		(at 16.891 -80.4545)
		(property "Reference" "R1D25"
			(at 0 0 0)
			(layer "F.SilkS")
			(hide yes)
			(effects
				(font
					(size 1.27 1.27)
				)
			)
		)
		(property "Value" ""
			(at 0 0 0)
			(layer "F.Fab")
			(effects
				(font
					(size 1.27 1.27)
				)
			)
		)
		(duplicate_pad_numbers_are_jumpers no)
		(fp_rect
			(start 0.2794 0.9906)
			(end -0.2794 -0.1016)
			(stroke
				(width 0)
				(type default)
			)
			(fill no)
			(layer "F.CrtYd")
		)
		(fp_line
			(start -0.2794 -0.1016)
			(end -0.2794 0.9906)
			(stroke
				(width 0.1)
				(type default)
			)
			(layer "F.Fab")
		)
		(fp_line
			(start -0.2794 0.9906)
			(end 0.2794 0.9906)
			(stroke
				(width 0.1)
				(type default)
			)
			(layer "F.Fab")
		)
		(fp_line
			(start 0.2794 -0.1016)
			(end -0.2794 -0.1016)
			(stroke
				(width 0.1)
				(type default)
			)
			(layer "F.Fab")
		)
		(fp_line
			(start 0.2794 0.9906)
			(end 0.2794 -0.1016)
			(stroke
				(width 0.1)
				(type default)
			)
			(layer "F.Fab")
		)
		(pad "1" smd rect
			(at 0 0)
			(size 0.508 0.508)
			(layers "F.Cu" "F.Mask" "F.Paste")
			(net "SMB_BMC_PMBUS_STBY_LVC3_SDA")
		)
		(pad "2" smd rect
			(at 0 0.889)
			(size 0.508 0.508)
			(layers "F.Cu" "F.Mask" "F.Paste")
			(net "SMB_3V3SB_HSC_SDA_R")
		)
		(zone
			(layer "F.Cu")
			(hatch none 0.5)
			(connect_pads
				(clearance 0)
			)
			(min_thickness 0.25)
			(keepout
				(tracks allowed)
				(vias not_allowed)
				(pads allowed)
				(copperpour not_allowed)
				(footprints allowed)
			)
			(placement
				(enabled no)
				(sheetname "")
			)
			(fill
				(thermal_gap 0.5)
				(thermal_bridge_width 0.5)
				(island_removal_mode 0)
			)
			(polygon
				(pts
					(xy 17.145 -79.8195) (xy 17.145 -80.2005) (xy 16.637 -80.2005) (xy 16.637 -79.8195)
				)
			)
		)
		(zone
			(layer "F.Cu")
			(hatch none 0.5)
			(connect_pads
				(clearance 0)
			)
			(min_thickness 0.25)
			(keepout
				(tracks not_allowed)
				(vias allowed)
				(pads allowed)
				(copperpour not_allowed)
				(footprints allowed)
			)
			(placement
				(enabled no)
				(sheetname "")
			)
			(fill
				(thermal_gap 0.5)
				(thermal_bridge_width 0.5)
				(island_removal_mode 0)
			)
			(polygon
				(pts
					(xy 17.145 -79.8195) (xy 17.145 -80.2005) (xy 16.637 -80.2005) (xy 16.637 -79.8195)
				)
			)
		)
	)
	(footprint ""
		(layer "F.Cu")
		(at 244.551454 -125.88113 -90)
		(property "Reference" "C5B2"
			(at 0 0 270)
			(layer "F.SilkS")
			(hide yes)
			(effects
				(font
					(size 1.27 1.27)
				)
			)
		)
		(property "Value" ""
			(at 0 0 270)
			(layer "F.Fab")
			(effects
				(font
					(size 1.27 1.27)
				)
			)
		)
		(duplicate_pad_numbers_are_jumpers no)
		(fp_rect
			(start -0.500126 1.598422)
			(end 0.500126 -0.201422)
			(stroke
				(width 0)
				(type default)
			)
			(fill no)
			(layer "F.CrtYd")
		)
		(fp_line
			(start -0.500126 1.598422)
			(end -0.500126 -0.201422)
			(stroke
				(width 0.1)
				(type default)
			)
			(layer "F.Fab")
		)
		(fp_line
			(start 0.500126 1.598422)
			(end -0.500126 1.598422)
			(stroke
				(width 0.1)
				(type default)
			)
			(layer "F.Fab")
		)
		(fp_line
			(start -0.500126 -0.201422)
			(end 0.500126 -0.201422)
			(stroke
				(width 0.1)
				(type default)
			)
			(layer "F.Fab")
		)
		(fp_line
			(start 0.500126 -0.201422)
			(end 0.500126 1.598422)
			(stroke
				(width 0.1)
				(type default)
			)
			(layer "F.Fab")
		)
		(pad "1" smd rect
			(at 0 0 180)
			(size 0.889 0.9906)
			(layers "F.Cu" "F.Mask" "F.Paste")
			(net "PVDDQ_DEF")
		)
		(pad "2" smd rect
			(at 0 1.397 180)
			(size 0.889 0.9906)
			(layers "F.Cu" "F.Mask" "F.Paste")
			(net "GND")
		)
		(zone
			(layer "F.Cu")
			(hatch none 0.5)
			(connect_pads
				(clearance 0)
			)
			(min_thickness 0.25)
			(keepout
				(tracks allowed)
				(vias not_allowed)
				(pads allowed)
				(copperpour not_allowed)
				(footprints allowed)
			)
			(placement
				(enabled no)
				(sheetname "")
			)
			(fill
				(thermal_gap 0.5)
				(thermal_bridge_width 0.5)
				(island_removal_mode 0)
			)
			(polygon
				(pts
					(xy 243.598954 -126.37643) (xy 243.598954 -125.38583) (xy 244.106954 -125.38583) (xy 244.106954 -126.37643)
				)
			)
		)
		(zone
			(layer "F.Cu")
			(hatch none 0.5)
			(connect_pads
				(clearance 0)
			)
			(min_thickness 0.25)
			(keepout
				(tracks not_allowed)
				(vias allowed)
				(pads allowed)
				(copperpour not_allowed)
				(footprints allowed)
			)
			(placement
				(enabled no)
				(sheetname "")
			)
			(fill
				(thermal_gap 0.5)
				(thermal_bridge_width 0.5)
				(island_removal_mode 0)
			)
			(polygon
				(pts
					(xy 243.598954 -126.37643) (xy 243.598954 -125.38583) (xy 244.106954 -125.38583) (xy 244.106954 -126.37643)
				)
			)
		)
	)
	(footprint ""
		(layer "F.Cu")
		(at 389.89 -87.3125 180)
		(property "Reference" "R3P2"
			(at 0 0 180)
			(layer "F.SilkS")
			(hide yes)
			(effects
				(font
					(size 1.27 1.27)
				)
			)
		)
		(property "Value" ""
			(at 0 0 180)
			(layer "F.Fab")
			(effects
				(font
					(size 1.27 1.27)
				)
			)
		)
		(duplicate_pad_numbers_are_jumpers no)
		(fp_poly
			(pts
				(xy -0.2794 -0.1016) (xy 0.2794 -0.1016) (xy 0.2794 0.9906) (xy -0.2794 0.9906)
			)
			(stroke
				(width 0)
				(type default)
			)
			(fill no)
			(layer "F.CrtYd")
		)
		(fp_line
			(start 0.2794 0.9906)
			(end 0.2794 -0.1016)
			(stroke
				(width 0.1)
				(type default)
			)
			(layer "F.Fab")
		)
		(fp_line
			(start 0.2794 -0.1016)
			(end -0.2794 -0.1016)
			(stroke
				(width 0.1)
				(type default)
			)
			(layer "F.Fab")
		)
		(fp_line
			(start -0.2794 0.9906)
			(end 0.2794 0.9906)
			(stroke
				(width 0.1)
				(type default)
			)
			(layer "F.Fab")
		)
		(fp_line
			(start -0.2794 -0.1016)
			(end -0.2794 0.9906)
			(stroke
				(width 0.1)
				(type default)
			)
			(layer "F.Fab")
		)
		(pad "1" smd rect
			(at 0 0 180)
			(size 0.508 0.508)
			(layers "F.Cu" "F.Mask" "F.Paste")
			(net "RMII_BMC_PCH_SPRNGVLLE_CRSDV")
		)
		(pad "2" smd rect
			(at 0 0.889 180)
			(size 0.508 0.508)
			(layers "F.Cu" "F.Mask" "F.Paste")
			(net "RMII_BMC_PCH_SPRNGVLLE_CRSDV_R1")
		)
		(zone
			(layer "F.Cu")
			(hatch none 0.5)
			(connect_pads
				(clearance 0)
			)
			(min_thickness 0.25)
			(keepout
				(tracks not_allowed)
				(vias allowed)
				(pads allowed)
				(copperpour not_allowed)
				(footprints allowed)
			)
			(placement
				(enabled no)
				(sheetname "")
			)
			(fill
				(thermal_gap 0.5)
				(thermal_bridge_width 0.5)
				(island_removal_mode 0)
			)
			(polygon
				(pts
					(xy 390.144 -87.9475) (xy 389.636 -87.9475) (xy 389.636 -87.5665) (xy 390.144 -87.5665)
				)
			)
		)
		(zone
			(layer "F.Cu")
			(hatch none 0.5)
			(connect_pads
				(clearance 0)
			)
			(min_thickness 0.25)
			(keepout
				(tracks allowed)
				(vias not_allowed)
				(pads allowed)
				(copperpour not_allowed)
				(footprints allowed)
			)
			(placement
				(enabled no)
				(sheetname "")
			)
			(fill
				(thermal_gap 0.5)
				(thermal_bridge_width 0.5)
				(island_removal_mode 0)
			)
			(polygon
				(pts
					(xy 390.144 -87.5665) (xy 389.636 -87.5665) (xy 389.636 -87.9475) (xy 390.144 -87.9475)
				)
			)
		)
	)
)
